FILE_TYPE=LIBRARY_PARTS;
primitive 'SW_PUSHBUTTON4P_24';
  pin
    '1':
      PIN_NUMBER='(1)';
      BIDIRECTIONAL='TRUE';
      INPUT_LOAD='(-0.01,0.01)';
      OUTPUT_LOAD='(1.0,-1.0)';
    '2':
      PIN_NUMBER='(2)';
      BIDIRECTIONAL='TRUE';
      INPUT_LOAD='(-0.01,0.01)';
      OUTPUT_LOAD='(1.0,-1.0)';
    '3':
      PIN_NUMBER='(3)';
      BIDIRECTIONAL='TRUE';
      INPUT_LOAD='(-0.01,0.01)';
      OUTPUT_LOAD='(1.0,-1.0)';
    '4':
      PIN_NUMBER='(4)';
      BIDIRECTIONAL='TRUE';
      INPUT_LOAD='(-0.01,0.01)';
      OUTPUT_LOAD='(1.0,-1.0)';
  end_pin;
  body
    PART_NAME='SW_PUSHBUTTON4P_24';
    BODY_NAME='SW_PUSHBUTTON4P_24';
    PHYS_DES_PREFIX='SW';
    CLASS='IO';
  end_body;
end_primitive;

END.
